(kicad_pcb
	(version 20240108)
	(generator "pcbnew")
	(generator_version "8.0")
	(general
		(thickness 1.62)
		(legacy_teardrops no)
	)
	(paper "A4")
	(title_block
		(title "Jetson Orin Baseboard")
		(date "2025-03-12")
		(rev "1.3.4")
		(company "Antmicro Ltd")
		(comment 1 "www.antmicro.com")
		(comment 9 "footprints 147-152 of 677")
	)
	(layers
		(0 "F.Cu" signal)
		(1 "In1.Cu" signal)
		(2 "In2.Cu" signal)
		(3 "In3.Cu" signal)
		(4 "In4.Cu" jumper)
		(5 "In5.Cu" signal)
		(6 "In6.Cu" signal)
		(31 "B.Cu" signal)
		(32 "B.Adhes" user "B.Adhesive")
		(33 "F.Adhes" user "F.Adhesive")
		(34 "B.Paste" user)
		(35 "F.Paste" user)
		(36 "B.SilkS" user "B.Silkscreen")
		(37 "F.SilkS" user "F.Silkscreen")
		(38 "B.Mask" user)
		(39 "F.Mask" user)
		(40 "Dwgs.User" user "User.Drawings")
		(41 "Cmts.User" user "User.Comments")
		(42 "Eco1.User" user "User.Eco1")
		(43 "Eco2.User" user "User.Eco2")
		(44 "Edge.Cuts" user)
		(45 "Margin" user)
		(46 "B.CrtYd" user "B.Courtyard")
		(47 "F.CrtYd" user "F.Courtyard")
		(48 "B.Fab" user)
		(49 "F.Fab" user)
	)
	(footprint "antmicro-footprints:R_0402_1005Metric"
		(layer "F.Cu")
		(at 86.55 103.8 180)
		(descr "Resistor SMD 0402")
		(tags "resistor SMD 0402")
		(property "Reference" "R208"
			(at 1.35 0.57 180)
			(layer "F.SilkS")
			(effects
				(font
					(size 0.7 0.7)
					(thickness 0.15)
				)
				(justify left bottom)
			)
		)
		(property "Value" "R_2k2_0402"
			(at 0 1.4 180)
			(layer "F.Fab")
			(effects
				(font
					(size 0.7 0.7)
					(thickness 0.15)
				)
				(justify left bottom)
			)
		)
		(property "Footprint" "antmicro-footprints:R_0402_1005Metric"
			(at 0 0 180)
			(layer "F.Fab")
			(hide yes)
			(effects
				(font
					(size 1.27 1.27)
					(thickness 0.15)
				)
			)
		)
		(property "Datasheet" "https://www.bourns.com/docs/product-datasheets/cr.pdf"
			(at 0 0 180)
			(layer "F.Fab")
			(hide yes)
			(effects
				(font
					(size 1.27 1.27)
					(thickness 0.15)
				)
			)
		)
		(property "Author" "Antmicro"
			(at 173.1 207.6 0)
			(layer "F.Fab")
			(hide yes)
			(effects
				(font
					(size 1 1)
					(thickness 0.15)
				)
			)
		)
		(property "License" "Apache-2.0"
			(at 173.1 207.6 0)
			(layer "F.Fab")
			(hide yes)
			(effects
				(font
					(size 1 1)
					(thickness 0.15)
				)
			)
		)
		(property "MPN" "CR0402-FX-2201GLF"
			(at 173.1 207.6 0)
			(layer "F.Fab")
			(hide yes)
			(effects
				(font
					(size 1 1)
					(thickness 0.15)
				)
			)
		)
		(property "Manufacturer" "Bourns"
			(at 173.1 207.6 0)
			(layer "F.Fab")
			(hide yes)
			(effects
				(font
					(size 1 1)
					(thickness 0.15)
				)
			)
		)
		(property "Tolerance" "1%"
			(at 173.1 207.6 0)
			(layer "F.Fab")
			(hide yes)
			(effects
				(font
					(size 1 1)
					(thickness 0.15)
				)
			)
		)
		(property "Val" "2k2"
			(at 173.1 207.6 0)
			(layer "F.Fab")
			(hide yes)
			(effects
				(font
					(size 1 1)
					(thickness 0.15)
				)
			)
		)
		(sheetname "HDMI")
		(sheetfile "hdmi.kicad_sch")
		(attr smd exclude_from_pos_files exclude_from_bom dnp)
		(fp_rect
			(start -0.925 -0.47)
			(end 0.925 0.47)
			(stroke
				(width 0.05)
				(type default)
			)
			(fill none)
			(layer "F.CrtYd")
		)
		(fp_rect
			(start -0.5 -0.25)
			(end 0.5 0.25)
			(stroke
				(width 0.15)
				(type solid)
			)
			(fill none)
			(layer "F.Fab")
		)
		(fp_text user "${REFERENCE}"
			(at -0.95 3.168 180)
			(layer "F.Fab")
			(hide yes)
			(effects
				(font
					(size 0.7 0.7)
					(thickness 0.15)
				)
				(justify left bottom)
			)
		)
		(fp_text user "Author: Antmicro"
			(at -0.95 4.169 180)
			(layer "F.Fab")
			(hide yes)
			(effects
				(font
					(size 0.7 0.7)
					(thickness 0.15)
				)
				(justify left bottom)
			)
		)
		(fp_text user "License: Apache-2.0"
			(at -0.95 5.169 180)
			(layer "F.Fab")
			(hide yes)
			(effects
				(font
					(size 0.7 0.7)
					(thickness 0.15)
				)
				(justify left bottom)
			)
		)
		(pad "1" smd roundrect
			(at -0.48 0 180)
			(size 0.59 0.64)
			(layers "F.Cu" "F.Paste" "F.Mask")
			(roundrect_rratio 0.25)
			(net 703 "/HDMI/HDMI_HPD")
			(pintype "passive")
		)
		(pad "2" smd roundrect
			(at 0.48 0 180)
			(size 0.59 0.64)
			(layers "F.Cu" "F.Paste" "F.Mask")
			(roundrect_rratio 0.25)
			(net 87 "+3V3")
			(pintype "passive")
		)
	)
	(footprint "antmicro-footprints:TP_SMD_0.75mm"
		(layer "F.Cu")
		(at 127.905 112.21 180)
		(property "Reference" "TP9"
			(at -0.425 -0.43 180)
			(layer "F.SilkS")
			(effects
				(font
					(size 0.7 0.7)
					(thickness 0.15)
				)
				(justify left bottom)
			)
		)
		(property "Value" "TP_0.75mm_SMD"
			(at 0 1.2 180)
			(layer "F.Fab")
			(effects
				(font
					(size 0.7 0.7)
					(thickness 0.15)
				)
				(justify left bottom)
			)
		)
		(property "Footprint" "antmicro-footprints:TP_SMD_0.75mm"
			(at 0 0 180)
			(layer "F.Fab")
			(hide yes)
			(effects
				(font
					(size 1.27 1.27)
					(thickness 0.15)
				)
			)
		)
		(property "Author" "Antmicro"
			(at 255.81 224.42 0)
			(layer "F.Fab")
			(hide yes)
			(effects
				(font
					(size 1 1)
					(thickness 0.15)
				)
			)
		)
		(property "License" "Apache-2.0"
			(at 255.81 224.42 0)
			(layer "F.Fab")
			(hide yes)
			(effects
				(font
					(size 1 1)
					(thickness 0.15)
				)
			)
		)
		(property "MPN" ""
			(at 255.81 224.42 0)
			(layer "F.Fab")
			(hide yes)
			(effects
				(font
					(size 1 1)
					(thickness 0.15)
				)
			)
		)
		(property "Manufacturer" ""
			(at 255.81 224.42 0)
			(layer "F.Fab")
			(hide yes)
			(effects
				(font
					(size 1 1)
					(thickness 0.15)
				)
			)
		)
		(sheetname "M.2")
		(sheetfile "m-2.kicad_sch")
		(attr exclude_from_pos_files exclude_from_bom)
		(fp_circle
			(center 0 0)
			(end 0.475 0)
			(stroke
				(width 0.05)
				(type default)
			)
			(fill none)
			(layer "F.CrtYd")
		)
		(fp_text user "Author: Antmicro"
			(at -0.4 3.901 180)
			(layer "F.Fab")
			(hide yes)
			(effects
				(font
					(size 0.7 0.7)
					(thickness 0.15)
				)
				(justify left bottom)
			)
		)
		(fp_text user "License: Apache-2.0"
			(at -0.4 5.101 180)
			(layer "F.Fab")
			(hide yes)
			(effects
				(font
					(size 0.7 0.7)
					(thickness 0.15)
				)
				(justify left bottom)
			)
		)
		(fp_text user "${REFERENCE}"
			(at -0.4 2.7 180)
			(layer "F.Fab")
			(hide yes)
			(effects
				(font
					(size 0.7 0.7)
					(thickness 0.15)
				)
				(justify left bottom)
			)
		)
		(pad "1" smd circle
			(at 0 0 180)
			(size 0.75 0.75)
			(layers "F.Cu" "F.Mask")
			(net 183 "/M.2/~{M2_E_UART_WAKE}")
			(pinfunction "1")
			(pintype "passive")
		)
	)
	(footprint "antmicro-footprints:R_0402_1005Metric"
		(layer "F.Cu")
		(at 105.15 120.75)
		(descr "Resistor SMD 0402")
		(tags "resistor SMD 0402")
		(property "Reference" "R138"
			(at -1.03 1.37 0)
			(layer "F.SilkS")
			(effects
				(font
					(size 0.7 0.7)
					(thickness 0.15)
				)
				(justify left bottom)
			)
		)
		(property "Value" "R_10k_0402"
			(at 0 1.4 0)
			(layer "F.Fab")
			(effects
				(font
					(size 0.7 0.7)
					(thickness 0.15)
				)
				(justify left bottom)
			)
		)
		(property "Footprint" "antmicro-footprints:R_0402_1005Metric"
			(at 0 0 0)
			(layer "F.Fab")
			(hide yes)
			(effects
				(font
					(size 1.27 1.27)
					(thickness 0.15)
				)
			)
		)
		(property "Datasheet" "https://www.bourns.com/docs/product-datasheets/cr.pdf"
			(at 0 0 0)
			(layer "F.Fab")
			(hide yes)
			(effects
				(font
					(size 1.27 1.27)
					(thickness 0.15)
				)
			)
		)
		(property "Author" "Antmicro"
			(at 0 0 0)
			(layer "F.Fab")
			(hide yes)
			(effects
				(font
					(size 1 1)
					(thickness 0.15)
				)
			)
		)
		(property "License" "Apache-2.0"
			(at 0 0 0)
			(layer "F.Fab")
			(hide yes)
			(effects
				(font
					(size 1 1)
					(thickness 0.15)
				)
			)
		)
		(property "MPN" "CR0402-FX-1002GLF"
			(at 0 0 0)
			(layer "F.Fab")
			(hide yes)
			(effects
				(font
					(size 1 1)
					(thickness 0.15)
				)
			)
		)
		(property "Manufacturer" "Bourns"
			(at 0 0 0)
			(layer "F.Fab")
			(hide yes)
			(effects
				(font
					(size 1 1)
					(thickness 0.15)
				)
			)
		)
		(property "Tolerance" "1%"
			(at 0 0 0)
			(layer "F.Fab")
			(hide yes)
			(effects
				(font
					(size 1 1)
					(thickness 0.15)
				)
			)
		)
		(property "Val" "10k"
			(at 0 0 0)
			(layer "F.Fab")
			(hide yes)
			(effects
				(font
					(size 1 1)
					(thickness 0.15)
				)
			)
		)
		(sheetname "USB3")
		(sheetfile "usb3.kicad_sch")
		(attr smd)
		(fp_rect
			(start -0.925 -0.47)
			(end 0.925 0.47)
			(stroke
				(width 0.05)
				(type default)
			)
			(fill none)
			(layer "F.CrtYd")
		)
		(fp_rect
			(start -0.5 -0.25)
			(end 0.5 0.25)
			(stroke
				(width 0.15)
				(type solid)
			)
			(fill none)
			(layer "F.Fab")
		)
		(fp_text user "${REFERENCE}"
			(at -0.95 3.168 0)
			(layer "F.Fab")
			(hide yes)
			(effects
				(font
					(size 0.7 0.7)
					(thickness 0.15)
				)
				(justify left bottom)
			)
		)
		(fp_text user "Author: Antmicro"
			(at -0.95 4.169 0)
			(layer "F.Fab")
			(hide yes)
			(effects
				(font
					(size 0.7 0.7)
					(thickness 0.15)
				)
				(justify left bottom)
			)
		)
		(fp_text user "License: Apache-2.0"
			(at -0.95 5.169 0)
			(layer "F.Fab")
			(hide yes)
			(effects
				(font
					(size 0.7 0.7)
					(thickness 0.15)
				)
				(justify left bottom)
			)
		)
		(pad "1" smd roundrect
			(at -0.48 0)
			(size 0.59 0.64)
			(layers "F.Cu" "F.Paste" "F.Mask")
			(roundrect_rratio 0.25)
			(net 508 "USBC1_FLG")
			(pintype "passive")
		)
		(pad "2" smd roundrect
			(at 0.48 0)
			(size 0.59 0.64)
			(layers "F.Cu" "F.Paste" "F.Mask")
			(roundrect_rratio 0.25)
			(net 87 "+3V3")
			(pintype "passive")
		)
	)
	(footprint "antmicro-footprints:R_0402_1005Metric"
		(layer "F.Cu")
		(at 42.115 103.541 180)
		(descr "Resistor SMD 0402")
		(tags "resistor SMD 0402")
		(property "Reference" "R229"
			(at 1.315 0.441 180)
			(layer "F.SilkS")
			(effects
				(font
					(size 0.7 0.7)
					(thickness 0.15)
				)
				(justify left bottom)
			)
		)
		(property "Value" "R_100k_0402"
			(at 0 1.4 180)
			(layer "F.Fab")
			(effects
				(font
					(size 0.7 0.7)
					(thickness 0.15)
				)
				(justify left bottom)
			)
		)
		(property "Footprint" "antmicro-footprints:R_0402_1005Metric"
			(at 0 0 180)
			(layer "F.Fab")
			(hide yes)
			(effects
				(font
					(size 1.27 1.27)
					(thickness 0.15)
				)
			)
		)
		(property "Datasheet" "https://www.bourns.com/docs/product-datasheets/cr.pdf"
			(at 0 0 180)
			(layer "F.Fab")
			(hide yes)
			(effects
				(font
					(size 1.27 1.27)
					(thickness 0.15)
				)
			)
		)
		(property "Author" "Antmicro"
			(at 84.23 207.082 0)
			(layer "F.Fab")
			(hide yes)
			(effects
				(font
					(size 1 1)
					(thickness 0.15)
				)
			)
		)
		(property "License" "Apache-2.0"
			(at 84.23 207.082 0)
			(layer "F.Fab")
			(hide yes)
			(effects
				(font
					(size 1 1)
					(thickness 0.15)
				)
			)
		)
		(property "MPN" "CR0402-FX-1003GLF"
			(at 84.23 207.082 0)
			(layer "F.Fab")
			(hide yes)
			(effects
				(font
					(size 1 1)
					(thickness 0.15)
				)
			)
		)
		(property "Manufacturer" "Bourns"
			(at 84.23 207.082 0)
			(layer "F.Fab")
			(hide yes)
			(effects
				(font
					(size 1 1)
					(thickness 0.15)
				)
			)
		)
		(property "Tolerance" "1%"
			(at 84.23 207.082 0)
			(layer "F.Fab")
			(hide yes)
			(effects
				(font
					(size 1 1)
					(thickness 0.15)
				)
			)
		)
		(property "Val" "100k"
			(at 84.23 207.082 0)
			(layer "F.Fab")
			(hide yes)
			(effects
				(font
					(size 1 1)
					(thickness 0.15)
				)
			)
		)
		(sheetname "Ethernet")
		(sheetfile "ethernet.kicad_sch")
		(attr smd exclude_from_pos_files exclude_from_bom dnp)
		(fp_rect
			(start -0.925 -0.47)
			(end 0.925 0.47)
			(stroke
				(width 0.05)
				(type default)
			)
			(fill none)
			(layer "F.CrtYd")
		)
		(fp_rect
			(start -0.5 -0.25)
			(end 0.5 0.25)
			(stroke
				(width 0.15)
				(type solid)
			)
			(fill none)
			(layer "F.Fab")
		)
		(fp_text user "License: Apache-2.0"
			(at -0.95 5.169 180)
			(layer "F.Fab")
			(hide yes)
			(effects
				(font
					(size 0.7 0.7)
					(thickness 0.15)
				)
				(justify left bottom)
			)
		)
		(fp_text user "${REFERENCE}"
			(at -0.95 3.168 180)
			(layer "F.Fab")
			(hide yes)
			(effects
				(font
					(size 0.7 0.7)
					(thickness 0.15)
				)
				(justify left bottom)
			)
		)
		(fp_text user "Author: Antmicro"
			(at -0.95 4.169 180)
			(layer "F.Fab")
			(hide yes)
			(effects
				(font
					(size 0.7 0.7)
					(thickness 0.15)
				)
				(justify left bottom)
			)
		)
		(pad "1" smd roundrect
			(at -0.48 0 180)
			(size 0.59 0.64)
			(layers "F.Cu" "F.Paste" "F.Mask")
			(roundrect_rratio 0.25)
			(net 106 "GNDD")
			(pintype "passive")
		)
		(pad "2" smd roundrect
			(at 0.48 0 180)
			(size 0.59 0.64)
			(layers "F.Cu" "F.Paste" "F.Mask")
			(roundrect_rratio 0.25)
			(net 650 "/Ethernet/ULS-12_CTRL")
			(pintype "passive")
		)
	)
	(footprint "antmicro-footprints:R_0402_1005Metric"
		(layer "F.Cu")
		(at 114.4 97 180)
		(descr "Resistor SMD 0402")
		(tags "resistor SMD 0402")
		(property "Reference" "R29"
			(at 3.95 1.05 180)
			(layer "F.SilkS")
			(effects
				(font
					(size 0.7 0.7)
					(thickness 0.15)
				)
				(justify left bottom)
			)
		)
		(property "Value" "R_0R_0402"
			(at 0 1.4 180)
			(layer "F.Fab")
			(effects
				(font
					(size 0.7 0.7)
					(thickness 0.15)
				)
				(justify left bottom)
			)
		)
		(property "Footprint" "antmicro-footprints:R_0402_1005Metric"
			(at 0 0 180)
			(layer "F.Fab")
			(hide yes)
			(effects
				(font
					(size 1.27 1.27)
					(thickness 0.15)
				)
			)
		)
		(property "Datasheet" "https://industrial.panasonic.com/cdbs/www-data/pdf/RDA0000/AOA0000C301.pdf"
			(at 0 0 180)
			(layer "F.Fab")
			(hide yes)
			(effects
				(font
					(size 1.27 1.27)
					(thickness 0.15)
				)
			)
		)
		(property "Author" "Antmicro"
			(at 228.8 194 0)
			(layer "F.Fab")
			(hide yes)
			(effects
				(font
					(size 1 1)
					(thickness 0.15)
				)
			)
		)
		(property "Current" "1A"
			(at 228.8 194 0)
			(layer "F.Fab")
			(hide yes)
			(effects
				(font
					(size 1 1)
					(thickness 0.15)
				)
			)
		)
		(property "License" "Apache-2.0"
			(at 228.8 194 0)
			(layer "F.Fab")
			(hide yes)
			(effects
				(font
					(size 1 1)
					(thickness 0.15)
				)
			)
		)
		(property "MPN" "ERJ2GE0R00X"
			(at 228.8 194 0)
			(layer "F.Fab")
			(hide yes)
			(effects
				(font
					(size 1 1)
					(thickness 0.15)
				)
			)
		)
		(property "Manufacturer" "Panasonic"
			(at 228.8 194 0)
			(layer "F.Fab")
			(hide yes)
			(effects
				(font
					(size 1 1)
					(thickness 0.15)
				)
			)
		)
		(property "Tolerance" ""
			(at 228.8 194 0)
			(layer "F.Fab")
			(hide yes)
			(effects
				(font
					(size 1 1)
					(thickness 0.15)
				)
			)
		)
		(property "Val" "0R"
			(at 228.8 194 0)
			(layer "F.Fab")
			(hide yes)
			(effects
				(font
					(size 1 1)
					(thickness 0.15)
				)
			)
		)
		(sheetname "M.2")
		(sheetfile "m-2.kicad_sch")
		(attr smd)
		(fp_rect
			(start -0.925 -0.47)
			(end 0.925 0.47)
			(stroke
				(width 0.05)
				(type default)
			)
			(fill none)
			(layer "F.CrtYd")
		)
		(fp_rect
			(start -0.5 -0.25)
			(end 0.5 0.25)
			(stroke
				(width 0.15)
				(type solid)
			)
			(fill none)
			(layer "F.Fab")
		)
		(fp_text user "${REFERENCE}"
			(at -0.95 3.168 180)
			(layer "F.Fab")
			(hide yes)
			(effects
				(font
					(size 0.7 0.7)
					(thickness 0.15)
				)
				(justify left bottom)
			)
		)
		(fp_text user "License: Apache-2.0"
			(at -0.95 5.169 180)
			(layer "F.Fab")
			(hide yes)
			(effects
				(font
					(size 0.7 0.7)
					(thickness 0.15)
				)
				(justify left bottom)
			)
		)
		(fp_text user "Author: Antmicro"
			(at -0.95 4.169 180)
			(layer "F.Fab")
			(hide yes)
			(effects
				(font
					(size 0.7 0.7)
					(thickness 0.15)
				)
				(justify left bottom)
			)
		)
		(pad "1" smd roundrect
			(at -0.48 0 180)
			(size 0.59 0.64)
			(layers "F.Cu" "F.Paste" "F.Mask")
			(roundrect_rratio 0.25)
			(net 216 "/M.2/M2_E_SUSCLK")
			(pintype "passive")
		)
		(pad "2" smd roundrect
			(at 0.48 0 180)
			(size 0.59 0.64)
			(layers "F.Cu" "F.Paste" "F.Mask")
			(roundrect_rratio 0.25)
			(net 456 "/M.2/32.7KHZ_OUT")
			(pintype "passive")
		)
	)
	(footprint "antmicro-footprints:R_0402_1005Metric"
		(layer "F.Cu")
		(at 105.154938 109)
		(descr "Resistor SMD 0402")
		(tags "resistor SMD 0402")
		(property "Reference" "R201"
			(at -3.654938 0.45 0)
			(layer "F.SilkS")
			(effects
				(font
					(size 0.7 0.7)
					(thickness 0.15)
				)
				(justify left bottom)
			)
		)
		(property "Value" "R_0R_0402"
			(at 0 1.4 0)
			(layer "F.Fab")
			(effects
				(font
					(size 0.7 0.7)
					(thickness 0.15)
				)
				(justify left bottom)
			)
		)
		(property "Footprint" "antmicro-footprints:R_0402_1005Metric"
			(at 0 0 0)
			(layer "F.Fab")
			(hide yes)
			(effects
				(font
					(size 1.27 1.27)
					(thickness 0.15)
				)
			)
		)
		(property "Datasheet" "https://industrial.panasonic.com/cdbs/www-data/pdf/RDA0000/AOA0000C301.pdf"
			(at 0 0 0)
			(layer "F.Fab")
			(hide yes)
			(effects
				(font
					(size 1.27 1.27)
					(thickness 0.15)
				)
			)
		)
		(property "Author" "Antmicro"
			(at 0 0 0)
			(layer "F.Fab")
			(hide yes)
			(effects
				(font
					(size 1 1)
					(thickness 0.15)
				)
			)
		)
		(property "Current" "1A"
			(at 0 0 0)
			(layer "F.Fab")
			(hide yes)
			(effects
				(font
					(size 1 1)
					(thickness 0.15)
				)
			)
		)
		(property "License" "Apache-2.0"
			(at 0 0 0)
			(layer "F.Fab")
			(hide yes)
			(effects
				(font
					(size 1 1)
					(thickness 0.15)
				)
			)
		)
		(property "MPN" "ERJ2GE0R00X"
			(at 0 0 0)
			(layer "F.Fab")
			(hide yes)
			(effects
				(font
					(size 1 1)
					(thickness 0.15)
				)
			)
		)
		(property "Manufacturer" "Panasonic"
			(at 0 0 0)
			(layer "F.Fab")
			(hide yes)
			(effects
				(font
					(size 1 1)
					(thickness 0.15)
				)
			)
		)
		(property "Tolerance" ""
			(at 0 0 0)
			(layer "F.Fab")
			(hide yes)
			(effects
				(font
					(size 1 1)
					(thickness 0.15)
				)
			)
		)
		(property "Val" "0R"
			(at 0 0 0)
			(layer "F.Fab")
			(hide yes)
			(effects
				(font
					(size 1 1)
					(thickness 0.15)
				)
			)
		)
		(sheetname "USB3")
		(sheetfile "usb3.kicad_sch")
		(attr smd)
		(fp_rect
			(start -0.925 -0.47)
			(end 0.925 0.47)
			(stroke
				(width 0.05)
				(type default)
			)
			(fill none)
			(layer "F.CrtYd")
		)
		(fp_rect
			(start -0.5 -0.25)
			(end 0.5 0.25)
			(stroke
				(width 0.15)
				(type solid)
			)
			(fill none)
			(layer "F.Fab")
		)
		(fp_text user "${REFERENCE}"
			(at -0.95 3.168 0)
			(layer "F.Fab")
			(hide yes)
			(effects
				(font
					(size 0.7 0.7)
					(thickness 0.15)
				)
				(justify left bottom)
			)
		)
		(fp_text user "Author: Antmicro"
			(at -0.95 4.169 0)
			(layer "F.Fab")
			(hide yes)
			(effects
				(font
					(size 0.7 0.7)
					(thickness 0.15)
				)
				(justify left bottom)
			)
		)
		(fp_text user "License: Apache-2.0"
			(at -0.95 5.169 0)
			(layer "F.Fab")
			(hide yes)
			(effects
				(font
					(size 0.7 0.7)
					(thickness 0.15)
				)
				(justify left bottom)
			)
		)
		(pad "1" smd roundrect
			(at -0.48 0)
			(size 0.59 0.64)
			(layers "F.Cu" "F.Paste" "F.Mask")
			(roundrect_rratio 0.25)
			(net 159 "USBSS2_RX_N")
			(pintype "passive")
		)
		(pad "2" smd roundrect
			(at 0.48 0)
			(size 0.59 0.64)
			(layers "F.Cu" "F.Paste" "F.Mask")
			(roundrect_rratio 0.25)
			(net 611 "/USB3/USBSS1_C_RX_P")
			(pintype "passive")
		)
	)
)
